(kicad_pcb
	(version 20260206)
	(generator "pcbnew")
	(generator_version "10.0")
	(general
		(thickness 1.6)
		(legacy_teardrops no)
	)
	(paper "A4")
	(title_block
		(title "9054_F0T_PDB_BD_GPU_F_V04_1213_1550_OCP.brd")
		(comment 1 "Grand Teton / footprints 20-24 of 608")
	)
	(layers
		(0 "F.Cu" signal "TOP")
		(4 "In1.Cu" signal "GND")
		(6 "In2.Cu" signal "IN1")
		(8 "In3.Cu" signal "GND1")
		(10 "In4.Cu" signal "VCC")
		(12 "In5.Cu" signal "VCC1")
		(14 "In6.Cu" signal "GND2")
		(16 "In7.Cu" signal "IN2")
		(18 "In8.Cu" signal "GND3")
		(2 "B.Cu" signal "BOTTOM")
		(9 "F.Adhes" user "F.Adhesive")
		(11 "B.Adhes" user "B.Adhesive")
		(13 "F.Paste" user "Package Geometry/Pastemask Top")
		(15 "B.Paste" user "Package Geometry/Pastemask Bottom")
		(5 "F.SilkS" user "Ref Des/Silkscreen Top")
		(7 "B.SilkS" user "Ref Des/Silkscreen Bottom")
		(1 "F.Mask" user "Board Geometry/Soldermask Top")
		(3 "B.Mask" user "Board Geometry/Soldermask Bottom")
		(17 "Dwgs.User" user "User.Drawings")
		(19 "Cmts.User" user "User.Comments")
		(21 "Eco1.User" user "User.Eco1")
		(23 "Eco2.User" user "User.Eco2")
		(25 "Edge.Cuts" user "Board Geometry/Outline")
		(27 "Margin" user)
		(31 "F.CrtYd" user "Package Geometry/Place Bound Top")
		(29 "B.CrtYd" user "Package Geometry/Place Bound Bottom")
		(35 "F.Fab" user "Ref Des/Assembly Top")
		(33 "B.Fab" user "Ref Des/Assembly Bottom")
	)
	(footprint ""
		(layer "F.Cu")
		(at 436.245 -29.083 180)
		(property "Reference" "R329"
			(at 0 0 180)
			(layer "F.SilkS")
			(hide yes)
			(effects
				(font
					(size 1.27 1.27)
				)
			)
		)
		(property "Value" ""
			(at 0 0 180)
			(layer "F.Fab")
			(effects
				(font
					(size 1.27 1.27)
				)
			)
		)
		(duplicate_pad_numbers_are_jumpers no)
		(fp_line
			(start 0.7874 0.4064)
			(end -0.7874 0.4064)
			(stroke
				(width 0.1524)
				(type default)
			)
			(layer "F.SilkS")
		)
		(fp_line
			(start 0.7874 -0.4064)
			(end 0.7874 0.4064)
			(stroke
				(width 0.1524)
				(type default)
			)
			(layer "F.SilkS")
		)
		(fp_line
			(start -0.7874 0.4064)
			(end -0.7874 -0.4064)
			(stroke
				(width 0.1524)
				(type default)
			)
			(layer "F.SilkS")
		)
		(fp_line
			(start -0.7874 -0.4064)
			(end 0.7874 -0.4064)
			(stroke
				(width 0.1524)
				(type default)
			)
			(layer "F.SilkS")
		)
		(fp_line
			(start 0.67945 0.3048)
			(end 0.120396 0.3048)
			(stroke
				(width 0.1)
				(type default)
			)
			(layer "F.Fab")
		)
		(fp_line
			(start 0.67945 -0.3048)
			(end 0.67945 0.3048)
			(stroke
				(width 0.1)
				(type default)
			)
			(layer "F.Fab")
		)
		(fp_line
			(start 0.12065 -0.2794)
			(end 0.12065 -0.3048)
			(stroke
				(width 0.1)
				(type default)
			)
			(layer "F.Fab")
		)
		(fp_line
			(start 0.12065 -0.3048)
			(end 0.67945 -0.3048)
			(stroke
				(width 0.1)
				(type default)
			)
			(layer "F.Fab")
		)
		(fp_line
			(start 0.120396 0.3048)
			(end 0.120396 0.2794)
			(stroke
				(width 0.1)
				(type default)
			)
			(layer "F.Fab")
		)
		(fp_line
			(start 0.120396 0.2794)
			(end -0.12065 0.2794)
			(stroke
				(width 0.1)
				(type default)
			)
			(layer "F.Fab")
		)
		(fp_line
			(start -0.12065 0.3048)
			(end -0.67945 0.3048)
			(stroke
				(width 0.1)
				(type default)
			)
			(layer "F.Fab")
		)
		(fp_line
			(start -0.12065 0.2794)
			(end -0.12065 0.3048)
			(stroke
				(width 0.1)
				(type default)
			)
			(layer "F.Fab")
		)
		(fp_line
			(start -0.12065 -0.2794)
			(end 0.12065 -0.2794)
			(stroke
				(width 0.1)
				(type default)
			)
			(layer "F.Fab")
		)
		(fp_line
			(start -0.12065 -0.305054)
			(end -0.12065 -0.2794)
			(stroke
				(width 0.1)
				(type default)
			)
			(layer "F.Fab")
		)
		(fp_line
			(start -0.67945 0.3048)
			(end -0.67945 -0.305054)
			(stroke
				(width 0.1)
				(type default)
			)
			(layer "F.Fab")
		)
		(fp_line
			(start -0.67945 -0.305054)
			(end -0.12065 -0.305054)
			(stroke
				(width 0.1)
				(type default)
			)
			(layer "F.Fab")
		)
		(pad "1" smd circle
			(at -0.40005 0 180)
			(size 0 0)
			(layers "F.Cu" "F.Mask" "F.Paste")
			(net "SMB_PDB_FAN_0_SDA")
		)
		(pad "2" smd circle
			(at 0.40005 0 180)
			(size 0 0)
			(layers "F.Cu" "F.Mask" "F.Paste")
			(net "P3V3_AUX")
		)
	)
	(footprint ""
		(layer "F.Cu")
		(at 99.568 -11.5062 -90)
		(property "Reference" "R163"
			(at 0 0 270)
			(layer "F.SilkS")
			(hide yes)
			(effects
				(font
					(size 1.27 1.27)
				)
			)
		)
		(property "Value" ""
			(at 0 0 270)
			(layer "F.Fab")
			(effects
				(font
					(size 1.27 1.27)
				)
			)
		)
		(duplicate_pad_numbers_are_jumpers no)
		(fp_line
			(start -0.7874 0.4064)
			(end -0.7874 -0.4064)
			(stroke
				(width 0.1524)
				(type default)
			)
			(layer "F.SilkS")
		)
		(fp_line
			(start 0.7874 0.4064)
			(end -0.7874 0.4064)
			(stroke
				(width 0.1524)
				(type default)
			)
			(layer "F.SilkS")
		)
		(fp_line
			(start -0.7874 -0.4064)
			(end 0.7874 -0.4064)
			(stroke
				(width 0.1524)
				(type default)
			)
			(layer "F.SilkS")
		)
		(fp_line
			(start 0.7874 -0.4064)
			(end 0.7874 0.4064)
			(stroke
				(width 0.1524)
				(type default)
			)
			(layer "F.SilkS")
		)
		(fp_line
			(start -0.67945 0.3048)
			(end -0.67945 -0.305054)
			(stroke
				(width 0.1)
				(type default)
			)
			(layer "F.Fab")
		)
		(fp_line
			(start -0.12065 0.3048)
			(end -0.67945 0.3048)
			(stroke
				(width 0.1)
				(type default)
			)
			(layer "F.Fab")
		)
		(fp_line
			(start 0.120396 0.3048)
			(end 0.120396 0.2794)
			(stroke
				(width 0.1)
				(type default)
			)
			(layer "F.Fab")
		)
		(fp_line
			(start 0.67945 0.3048)
			(end 0.120396 0.3048)
			(stroke
				(width 0.1)
				(type default)
			)
			(layer "F.Fab")
		)
		(fp_line
			(start -0.12065 0.2794)
			(end -0.12065 0.3048)
			(stroke
				(width 0.1)
				(type default)
			)
			(layer "F.Fab")
		)
		(fp_line
			(start 0.120396 0.2794)
			(end -0.12065 0.2794)
			(stroke
				(width 0.1)
				(type default)
			)
			(layer "F.Fab")
		)
		(fp_line
			(start -0.12065 -0.2794)
			(end 0.12065 -0.2794)
			(stroke
				(width 0.1)
				(type default)
			)
			(layer "F.Fab")
		)
		(fp_line
			(start 0.12065 -0.2794)
			(end 0.12065 -0.3048)
			(stroke
				(width 0.1)
				(type default)
			)
			(layer "F.Fab")
		)
		(fp_line
			(start 0.12065 -0.3048)
			(end 0.67945 -0.3048)
			(stroke
				(width 0.1)
				(type default)
			)
			(layer "F.Fab")
		)
		(fp_line
			(start 0.67945 -0.3048)
			(end 0.67945 0.3048)
			(stroke
				(width 0.1)
				(type default)
			)
			(layer "F.Fab")
		)
		(fp_line
			(start -0.67945 -0.305054)
			(end -0.12065 -0.305054)
			(stroke
				(width 0.1)
				(type default)
			)
			(layer "F.Fab")
		)
		(fp_line
			(start -0.12065 -0.305054)
			(end -0.12065 -0.2794)
			(stroke
				(width 0.1)
				(type default)
			)
			(layer "F.Fab")
		)
		(pad "1" smd circle
			(at -0.40005 0 270)
			(size 0 0)
			(layers "F.Cu" "F.Mask" "F.Paste")
			(net "PWRGD_P52V_HS2_4287_PG_R_N")
		)
		(pad "2" smd circle
			(at 0.40005 0 270)
			(size 0 0)
			(layers "F.Cu" "F.Mask" "F.Paste")
			(net "GND")
		)
	)
	(footprint ""
		(layer "F.Cu")
		(at 58.59399 -32.766 90)
		(property "Reference" "PD10"
			(at 2.413 3.91668 90)
			(unlocked yes)
			(layer "F.SilkS")
			(effects
				(font
					(size 0.7874 0.5842)
					(thickness 0.1524)
				)
				(justify left)
			)
		)
		(property "Value" ""
			(at 0 0 90)
			(layer "F.Fab")
			(effects
				(font
					(size 1.27 1.27)
				)
			)
		)
		(duplicate_pad_numbers_are_jumpers no)
		(fp_line
			(start 4.826 -3.109976)
			(end 4.826 0)
			(stroke
				(width 0.1524)
				(type default)
			)
			(layer "F.SilkS")
		)
		(fp_line
			(start 4.8133 -3.109976)
			(end 5.3467 -3.109976)
			(stroke
				(width 0.1524)
				(type default)
			)
			(layer "F.SilkS")
		)
		(fp_line
			(start -4.826 -3.109976)
			(end 4.826 -3.109976)
			(stroke
				(width 0.1524)
				(type default)
			)
			(layer "F.SilkS")
		)
		(fp_line
			(start -1.016 -1.016)
			(end -1.016 1.016)
			(stroke
				(width 0.1524)
				(type default)
			)
			(layer "F.SilkS")
		)
		(fp_line
			(start 5.334 0)
			(end 5.334 -3.109976)
			(stroke
				(width 0.1524)
				(type default)
			)
			(layer "F.SilkS")
		)
		(fp_line
			(start 4.826 0)
			(end 4.826 3.109976)
			(stroke
				(width 0.1524)
				(type default)
			)
			(layer "F.SilkS")
		)
		(fp_line
			(start 1.143 0)
			(end -1.016 -1.016)
			(stroke
				(width 0.1524)
				(type default)
			)
			(layer "F.SilkS")
		)
		(fp_line
			(start 1.143 0)
			(end 1.8034 0)
			(stroke
				(width 0.1524)
				(type default)
			)
			(layer "F.SilkS")
		)
		(fp_line
			(start -1.0922 0)
			(end -1.7018 0)
			(stroke
				(width 0.1524)
				(type default)
			)
			(layer "F.SilkS")
		)
		(fp_line
			(start -4.826 0)
			(end -4.826 -3.109976)
			(stroke
				(width 0.1524)
				(type default)
			)
			(layer "F.SilkS")
		)
		(fp_line
			(start -1.016 1.016)
			(end 1.016 0)
			(stroke
				(width 0.1524)
				(type default)
			)
			(layer "F.SilkS")
		)
		(fp_line
			(start 1.143 1.397)
			(end 1.143 -1.397)
			(stroke
				(width 0.1524)
				(type default)
			)
			(layer "F.SilkS")
		)
		(fp_line
			(start 5.334 3.109976)
			(end 5.334 0)
			(stroke
				(width 0.1524)
				(type default)
			)
			(layer "F.SilkS")
		)
		(fp_line
			(start 5.334 3.109976)
			(end 4.8133 3.109976)
			(stroke
				(width 0.1524)
				(type default)
			)
			(layer "F.SilkS")
		)
		(fp_line
			(start 5.207 3.109976)
			(end 5.207 -3.109976)
			(stroke
				(width 0.1524)
				(type default)
			)
			(layer "F.SilkS")
		)
		(fp_line
			(start 5.1308 3.109976)
			(end 5.1308 -3.109976)
			(stroke
				(width 0.1524)
				(type default)
			)
			(layer "F.SilkS")
		)
		(fp_line
			(start 5.0292 3.109976)
			(end 5.0292 -3.109976)
			(stroke
				(width 0.1524)
				(type default)
			)
			(layer "F.SilkS")
		)
		(fp_line
			(start 4.9276 3.109976)
			(end 4.9276 -3.109976)
			(stroke
				(width 0.1524)
				(type default)
			)
			(layer "F.SilkS")
		)
		(fp_line
			(start 4.826 3.109976)
			(end -4.826 3.109976)
			(stroke
				(width 0.1524)
				(type default)
			)
			(layer "F.SilkS")
		)
		(fp_line
			(start -4.826 3.109976)
			(end -4.826 0)
			(stroke
				(width 0.1524)
				(type default)
			)
			(layer "F.SilkS")
		)
		(fp_line
			(start 3.554984 -3.109976)
			(end 3.554984 3.109976)
			(stroke
				(width 0.1)
				(type default)
			)
			(layer "F.Fab")
		)
		(fp_line
			(start -3.554984 -3.109976)
			(end 3.554984 -3.109976)
			(stroke
				(width 0.1)
				(type default)
			)
			(layer "F.Fab")
		)
		(fp_line
			(start -1.016 -1.016)
			(end -1.016 1.016)
			(stroke
				(width 0.1)
				(type default)
			)
			(layer "F.Fab")
		)
		(fp_line
			(start 1.143 0)
			(end -1.016 -1.016)
			(stroke
				(width 0.1)
				(type default)
			)
			(layer "F.Fab")
		)
		(fp_line
			(start 1.143 0)
			(end 1.8034 0)
			(stroke
				(width 0.1)
				(type default)
			)
			(layer "F.Fab")
		)
		(fp_line
			(start -1.0922 0)
			(end -1.7018 0)
			(stroke
				(width 0.1)
				(type default)
			)
			(layer "F.Fab")
		)
		(fp_line
			(start -1.016 1.016)
			(end 1.016 0)
			(stroke
				(width 0.1)
				(type default)
			)
			(layer "F.Fab")
		)
		(fp_line
			(start 1.143 1.397)
			(end 1.143 -1.397)
			(stroke
				(width 0.1)
				(type default)
			)
			(layer "F.Fab")
		)
		(fp_line
			(start 3.554984 3.109976)
			(end -3.554984 3.109976)
			(stroke
				(width 0.1)
				(type default)
			)
			(layer "F.Fab")
		)
		(fp_line
			(start -3.554984 3.109976)
			(end -3.554984 -3.109976)
			(stroke
				(width 0.1)
				(type default)
			)
			(layer "F.Fab")
		)
		(fp_text user "+"
			(at -4.5466 0.19685 270)
			(unlocked yes)
			(layer "F.SilkS")
			(effects
				(font
					(size 1.905 1.4224)
					(thickness 0.1524)
				)
				(justify left)
			)
		)
		(fp_text user "-"
			(at 6.6802 0.22225 270)
			(unlocked yes)
			(layer "F.SilkS")
			(effects
				(font
					(size 1.905 1.4224)
					(thickness 0.1524)
				)
				(justify left)
			)
		)
		(fp_text user "+"
			(at -4.5466 0.19685 270)
			(unlocked yes)
			(layer "F.Fab")
			(effects
				(font
					(size 1.905 1.4224)
					(thickness 0.1524)
				)
				(justify left)
			)
		)
		(fp_text user "-"
			(at 6.6802 0.22225 270)
			(unlocked yes)
			(layer "F.Fab")
			(effects
				(font
					(size 1.905 1.4224)
					(thickness 0.1524)
				)
				(justify left)
			)
		)
		(pad "A" smd rect
			(at -3.400044 0 270)
			(size 2.5146 3.302)
			(layers "F.Cu" "F.Mask" "F.Paste")
			(net "GND")
		)
		(pad "C" smd rect
			(at 3.400044 0 270)
			(size 2.5146 3.302)
			(layers "F.Cu" "F.Mask" "F.Paste")
			(net "P52V_HS2")
		)
	)
	(footprint ""
		(layer "F.Cu")
		(at 166.543736 -63.881 180)
		(property "Reference" "PR7035"
			(at 0 0 180)
			(layer "F.SilkS")
			(hide yes)
			(effects
				(font
					(size 1.27 1.27)
				)
			)
		)
		(property "Value" ""
			(at 0 0 180)
			(layer "F.Fab")
			(effects
				(font
					(size 1.27 1.27)
				)
			)
		)
		(duplicate_pad_numbers_are_jumpers no)
		(fp_line
			(start 0.7874 0.4064)
			(end -0.7874 0.4064)
			(stroke
				(width 0.1524)
				(type default)
			)
			(layer "F.SilkS")
		)
		(fp_line
			(start 0.7874 -0.4064)
			(end 0.7874 0.4064)
			(stroke
				(width 0.1524)
				(type default)
			)
			(layer "F.SilkS")
		)
		(fp_line
			(start -0.7874 0.4064)
			(end -0.7874 -0.4064)
			(stroke
				(width 0.1524)
				(type default)
			)
			(layer "F.SilkS")
		)
		(fp_line
			(start -0.7874 -0.4064)
			(end 0.7874 -0.4064)
			(stroke
				(width 0.1524)
				(type default)
			)
			(layer "F.SilkS")
		)
		(fp_line
			(start 0.67945 0.3048)
			(end 0.120396 0.3048)
			(stroke
				(width 0.1)
				(type default)
			)
			(layer "F.Fab")
		)
		(fp_line
			(start 0.67945 -0.3048)
			(end 0.67945 0.3048)
			(stroke
				(width 0.1)
				(type default)
			)
			(layer "F.Fab")
		)
		(fp_line
			(start 0.12065 -0.2794)
			(end 0.12065 -0.3048)
			(stroke
				(width 0.1)
				(type default)
			)
			(layer "F.Fab")
		)
		(fp_line
			(start 0.12065 -0.3048)
			(end 0.67945 -0.3048)
			(stroke
				(width 0.1)
				(type default)
			)
			(layer "F.Fab")
		)
		(fp_line
			(start 0.120396 0.3048)
			(end 0.120396 0.2794)
			(stroke
				(width 0.1)
				(type default)
			)
			(layer "F.Fab")
		)
		(fp_line
			(start 0.120396 0.2794)
			(end -0.12065 0.2794)
			(stroke
				(width 0.1)
				(type default)
			)
			(layer "F.Fab")
		)
		(fp_line
			(start -0.12065 0.3048)
			(end -0.67945 0.3048)
			(stroke
				(width 0.1)
				(type default)
			)
			(layer "F.Fab")
		)
		(fp_line
			(start -0.12065 0.2794)
			(end -0.12065 0.3048)
			(stroke
				(width 0.1)
				(type default)
			)
			(layer "F.Fab")
		)
		(fp_line
			(start -0.12065 -0.2794)
			(end 0.12065 -0.2794)
			(stroke
				(width 0.1)
				(type default)
			)
			(layer "F.Fab")
		)
		(fp_line
			(start -0.12065 -0.305054)
			(end -0.12065 -0.2794)
			(stroke
				(width 0.1)
				(type default)
			)
			(layer "F.Fab")
		)
		(fp_line
			(start -0.67945 0.3048)
			(end -0.67945 -0.305054)
			(stroke
				(width 0.1)
				(type default)
			)
			(layer "F.Fab")
		)
		(fp_line
			(start -0.67945 -0.305054)
			(end -0.12065 -0.305054)
			(stroke
				(width 0.1)
				(type default)
			)
			(layer "F.Fab")
		)
		(pad "1" smd circle
			(at -0.40005 0 180)
			(size 0 0)
			(layers "F.Cu" "F.Mask" "F.Paste")
			(net "P52V_HS2_ESTART")
		)
		(pad "2" smd circle
			(at 0.40005 0 180)
			(size 0 0)
			(layers "F.Cu" "F.Mask" "F.Paste")
			(net "GND1_FIELD_SIGNAL")
		)
	)
	(footprint ""
		(layer "F.Cu")
		(at 466.639656 -107.502452 90)
		(property "Reference" "R86"
			(at 0 0 90)
			(layer "F.SilkS")
			(hide yes)
			(effects
				(font
					(size 1.27 1.27)
				)
			)
		)
		(property "Value" ""
			(at 0 0 90)
			(layer "F.Fab")
			(effects
				(font
					(size 1.27 1.27)
				)
			)
		)
		(duplicate_pad_numbers_are_jumpers no)
		(fp_line
			(start 0.7874 -0.4064)
			(end 0.7874 0.4064)
			(stroke
				(width 0.1524)
				(type default)
			)
			(layer "F.SilkS")
		)
		(fp_line
			(start -0.7874 -0.4064)
			(end 0.7874 -0.4064)
			(stroke
				(width 0.1524)
				(type default)
			)
			(layer "F.SilkS")
		)
		(fp_line
			(start 0.7874 0.4064)
			(end -0.7874 0.4064)
			(stroke
				(width 0.1524)
				(type default)
			)
			(layer "F.SilkS")
		)
		(fp_line
			(start -0.7874 0.4064)
			(end -0.7874 -0.4064)
			(stroke
				(width 0.1524)
				(type default)
			)
			(layer "F.SilkS")
		)
		(fp_line
			(start -0.12065 -0.305054)
			(end -0.12065 -0.2794)
			(stroke
				(width 0.1)
				(type default)
			)
			(layer "F.Fab")
		)
		(fp_line
			(start -0.67945 -0.305054)
			(end -0.12065 -0.305054)
			(stroke
				(width 0.1)
				(type default)
			)
			(layer "F.Fab")
		)
		(fp_line
			(start 0.67945 -0.3048)
			(end 0.67945 0.3048)
			(stroke
				(width 0.1)
				(type default)
			)
			(layer "F.Fab")
		)
		(fp_line
			(start 0.12065 -0.3048)
			(end 0.67945 -0.3048)
			(stroke
				(width 0.1)
				(type default)
			)
			(layer "F.Fab")
		)
		(fp_line
			(start 0.12065 -0.2794)
			(end 0.12065 -0.3048)
			(stroke
				(width 0.1)
				(type default)
			)
			(layer "F.Fab")
		)
		(fp_line
			(start -0.12065 -0.2794)
			(end 0.12065 -0.2794)
			(stroke
				(width 0.1)
				(type default)
			)
			(layer "F.Fab")
		)
		(fp_line
			(start 0.120396 0.2794)
			(end -0.12065 0.2794)
			(stroke
				(width 0.1)
				(type default)
			)
			(layer "F.Fab")
		)
		(fp_line
			(start -0.12065 0.2794)
			(end -0.12065 0.3048)
			(stroke
				(width 0.1)
				(type default)
			)
			(layer "F.Fab")
		)
		(fp_line
			(start 0.67945 0.3048)
			(end 0.120396 0.3048)
			(stroke
				(width 0.1)
				(type default)
			)
			(layer "F.Fab")
		)
		(fp_line
			(start 0.120396 0.3048)
			(end 0.120396 0.2794)
			(stroke
				(width 0.1)
				(type default)
			)
			(layer "F.Fab")
		)
		(fp_line
			(start -0.12065 0.3048)
			(end -0.67945 0.3048)
			(stroke
				(width 0.1)
				(type default)
			)
			(layer "F.Fab")
		)
		(fp_line
			(start -0.67945 0.3048)
			(end -0.67945 -0.305054)
			(stroke
				(width 0.1)
				(type default)
			)
			(layer "F.Fab")
		)
		(pad "1" smd circle
			(at -0.40005 0 90)
			(size 0 0)
			(layers "F.Cu" "F.Mask" "F.Paste")
			(net "SMB_P52V_SCL")
		)
		(pad "2" smd circle
			(at 0.40005 0 90)
			(size 0 0)
			(layers "F.Cu" "F.Mask" "F.Paste")
			(net "SMB_P52V_R_SCL")
		)
	)
)
